(kicad_pcb
	(version 20260206)
	(generator "pcbnew")
	(generator_version "10.0")
	(general
		(thickness 1.6)
		(legacy_teardrops no)
	)
	(paper "A4")
	(title_block
		(title "03242023_DA0F0TMBIJ0_F0T_Motherboard_J_brd_V01_OCP.brd")
		(comment 1 "Grand Teton / footprints 2156-2162 of 6105")
	)
	(layers
		(0 "F.Cu" signal "TOP")
		(4 "In1.Cu" signal "GND")
		(6 "In2.Cu" signal "IN1")
		(8 "In3.Cu" signal "GND1")
		(10 "In4.Cu" signal "IN2")
		(12 "In5.Cu" signal "GND2")
		(14 "In6.Cu" signal "IN3")
		(16 "In7.Cu" signal "GND3")
		(18 "In8.Cu" signal "VCC")
		(20 "In9.Cu" signal "VCC1")
		(22 "In10.Cu" signal "GND4")
		(24 "In11.Cu" signal "IN4")
		(26 "In12.Cu" signal "GND5")
		(28 "In13.Cu" signal "IN5")
		(30 "In14.Cu" signal "GND6")
		(32 "In15.Cu" signal "IN6")
		(34 "In16.Cu" signal "GND7")
		(2 "B.Cu" signal "BOTTOM")
		(9 "F.Adhes" user "F.Adhesive")
		(11 "B.Adhes" user "B.Adhesive")
		(13 "F.Paste" user "Package Geometry/Pastemask Top")
		(15 "B.Paste" user "Package Geometry/Pastemask Bottom")
		(5 "F.SilkS" user "Ref Des/Silkscreen Top")
		(7 "B.SilkS" user "Ref Des/Silkscreen Bottom")
		(1 "F.Mask" user "Board Geometry/Soldermask Top")
		(3 "B.Mask" user "Board Geometry/Soldermask Bottom")
		(17 "Dwgs.User" user "User.Drawings")
		(19 "Cmts.User" user "User.Comments")
		(21 "Eco1.User" user "User.Eco1")
		(23 "Eco2.User" user "User.Eco2")
		(25 "Edge.Cuts" user "Board Geometry/Outline")
		(27 "Margin" user)
		(31 "F.CrtYd" user "Package Geometry/Place Bound Top")
		(29 "B.CrtYd" user "Package Geometry/Place Bound Bottom")
		(35 "F.Fab" user "Ref Des/Assembly Top")
		(33 "B.Fab" user "Ref Des/Assembly Bottom")
	)
	(footprint ""
		(layer "F.Cu")
		(at 194.056 -92.801948 90)
		(property "Reference" "R4606"
			(at 0 0 90)
			(layer "F.SilkS")
			(hide yes)
			(effects
				(font
					(size 1.27 1.27)
				)
			)
		)
		(property "Value" ""
			(at 0 0 90)
			(layer "F.Fab")
			(effects
				(font
					(size 1.27 1.27)
				)
			)
		)
		(duplicate_pad_numbers_are_jumpers no)
		(fp_line
			(start 0.7874 -0.4064)
			(end 0.7874 0.4064)
			(stroke
				(width 0.1524)
				(type default)
			)
			(layer "F.SilkS")
		)
		(fp_line
			(start -0.7874 -0.4064)
			(end 0.7874 -0.4064)
			(stroke
				(width 0.1524)
				(type default)
			)
			(layer "F.SilkS")
		)
		(fp_line
			(start 0.7874 0.4064)
			(end -0.7874 0.4064)
			(stroke
				(width 0.1524)
				(type default)
			)
			(layer "F.SilkS")
		)
		(fp_line
			(start -0.7874 0.4064)
			(end -0.7874 -0.4064)
			(stroke
				(width 0.1524)
				(type default)
			)
			(layer "F.SilkS")
		)
		(fp_line
			(start -0.12065 -0.305054)
			(end -0.12065 -0.2794)
			(stroke
				(width 0.1)
				(type default)
			)
			(layer "F.Fab")
		)
		(fp_line
			(start -0.67945 -0.305054)
			(end -0.12065 -0.305054)
			(stroke
				(width 0.1)
				(type default)
			)
			(layer "F.Fab")
		)
		(fp_line
			(start 0.67945 -0.3048)
			(end 0.67945 0.3048)
			(stroke
				(width 0.1)
				(type default)
			)
			(layer "F.Fab")
		)
		(fp_line
			(start 0.12065 -0.3048)
			(end 0.67945 -0.3048)
			(stroke
				(width 0.1)
				(type default)
			)
			(layer "F.Fab")
		)
		(fp_line
			(start 0.12065 -0.2794)
			(end 0.12065 -0.3048)
			(stroke
				(width 0.1)
				(type default)
			)
			(layer "F.Fab")
		)
		(fp_line
			(start -0.12065 -0.2794)
			(end 0.12065 -0.2794)
			(stroke
				(width 0.1)
				(type default)
			)
			(layer "F.Fab")
		)
		(fp_line
			(start 0.120396 0.2794)
			(end -0.12065 0.2794)
			(stroke
				(width 0.1)
				(type default)
			)
			(layer "F.Fab")
		)
		(fp_line
			(start -0.12065 0.2794)
			(end -0.12065 0.3048)
			(stroke
				(width 0.1)
				(type default)
			)
			(layer "F.Fab")
		)
		(fp_line
			(start 0.67945 0.3048)
			(end 0.120396 0.3048)
			(stroke
				(width 0.1)
				(type default)
			)
			(layer "F.Fab")
		)
		(fp_line
			(start 0.120396 0.3048)
			(end 0.120396 0.2794)
			(stroke
				(width 0.1)
				(type default)
			)
			(layer "F.Fab")
		)
		(fp_line
			(start -0.12065 0.3048)
			(end -0.67945 0.3048)
			(stroke
				(width 0.1)
				(type default)
			)
			(layer "F.Fab")
		)
		(fp_line
			(start -0.67945 0.3048)
			(end -0.67945 -0.305054)
			(stroke
				(width 0.1)
				(type default)
			)
			(layer "F.Fab")
		)
		(pad "1" smd circle
			(at -0.40005 0 90)
			(size 0 0)
			(layers "F.Cu" "F.Mask" "F.Paste")
			(net "E1S_0_LED_ACT_R_N")
		)
		(pad "2" smd circle
			(at 0.40005 0 90)
			(size 0 0)
			(layers "F.Cu" "F.Mask" "F.Paste")
			(net "E1S_0_LED_ACT_N")
		)
	)
	(footprint ""
		(layer "F.Cu")
		(at 430.600104 -136.526778 180)
		(property "Reference" "R2596"
			(at 0 0 180)
			(layer "F.SilkS")
			(hide yes)
			(effects
				(font
					(size 1.27 1.27)
				)
			)
		)
		(property "Value" ""
			(at 0 0 180)
			(layer "F.Fab")
			(effects
				(font
					(size 1.27 1.27)
				)
			)
		)
		(duplicate_pad_numbers_are_jumpers no)
		(fp_line
			(start 0.7874 0.4064)
			(end -0.7874 0.4064)
			(stroke
				(width 0.1524)
				(type default)
			)
			(layer "F.SilkS")
		)
		(fp_line
			(start 0.7874 -0.4064)
			(end 0.7874 0.4064)
			(stroke
				(width 0.1524)
				(type default)
			)
			(layer "F.SilkS")
		)
		(fp_line
			(start -0.7874 0.4064)
			(end -0.7874 -0.4064)
			(stroke
				(width 0.1524)
				(type default)
			)
			(layer "F.SilkS")
		)
		(fp_line
			(start -0.7874 -0.4064)
			(end 0.7874 -0.4064)
			(stroke
				(width 0.1524)
				(type default)
			)
			(layer "F.SilkS")
		)
		(fp_line
			(start 0.67945 0.3048)
			(end 0.120396 0.3048)
			(stroke
				(width 0.1)
				(type default)
			)
			(layer "F.Fab")
		)
		(fp_line
			(start 0.67945 -0.3048)
			(end 0.67945 0.3048)
			(stroke
				(width 0.1)
				(type default)
			)
			(layer "F.Fab")
		)
		(fp_line
			(start 0.12065 -0.2794)
			(end 0.12065 -0.3048)
			(stroke
				(width 0.1)
				(type default)
			)
			(layer "F.Fab")
		)
		(fp_line
			(start 0.12065 -0.3048)
			(end 0.67945 -0.3048)
			(stroke
				(width 0.1)
				(type default)
			)
			(layer "F.Fab")
		)
		(fp_line
			(start 0.120396 0.3048)
			(end 0.120396 0.2794)
			(stroke
				(width 0.1)
				(type default)
			)
			(layer "F.Fab")
		)
		(fp_line
			(start 0.120396 0.2794)
			(end -0.12065 0.2794)
			(stroke
				(width 0.1)
				(type default)
			)
			(layer "F.Fab")
		)
		(fp_line
			(start -0.12065 0.3048)
			(end -0.67945 0.3048)
			(stroke
				(width 0.1)
				(type default)
			)
			(layer "F.Fab")
		)
		(fp_line
			(start -0.12065 0.2794)
			(end -0.12065 0.3048)
			(stroke
				(width 0.1)
				(type default)
			)
			(layer "F.Fab")
		)
		(fp_line
			(start -0.12065 -0.2794)
			(end 0.12065 -0.2794)
			(stroke
				(width 0.1)
				(type default)
			)
			(layer "F.Fab")
		)
		(fp_line
			(start -0.12065 -0.305054)
			(end -0.12065 -0.2794)
			(stroke
				(width 0.1)
				(type default)
			)
			(layer "F.Fab")
		)
		(fp_line
			(start -0.67945 0.3048)
			(end -0.67945 -0.305054)
			(stroke
				(width 0.1)
				(type default)
			)
			(layer "F.Fab")
		)
		(fp_line
			(start -0.67945 -0.305054)
			(end -0.12065 -0.305054)
			(stroke
				(width 0.1)
				(type default)
			)
			(layer "F.Fab")
		)
		(pad "1" smd circle
			(at -0.40005 0 180)
			(size 0 0)
			(layers "F.Cu" "F.Mask" "F.Paste")
			(net "SVID_CLK0_CPU0_R")
		)
		(pad "2" smd circle
			(at 0.40005 0 180)
			(size 0 0)
			(layers "F.Cu" "F.Mask" "F.Paste")
			(net "SVID_CLK_PVCCINFAON_CPU0_R")
		)
	)
	(footprint ""
		(layer "F.Cu")
		(at 116.367306 -29.450792)
		(property "Reference" "R3191"
			(at 0 0 0)
			(layer "F.SilkS")
			(hide yes)
			(effects
				(font
					(size 1.27 1.27)
				)
			)
		)
		(property "Value" ""
			(at 0 0 0)
			(layer "F.Fab")
			(effects
				(font
					(size 1.27 1.27)
				)
			)
		)
		(duplicate_pad_numbers_are_jumpers no)
		(fp_line
			(start -0.7874 -0.4064)
			(end 0.7874 -0.4064)
			(stroke
				(width 0.1524)
				(type default)
			)
			(layer "F.SilkS")
		)
		(fp_line
			(start -0.7874 0.4064)
			(end -0.7874 -0.4064)
			(stroke
				(width 0.1524)
				(type default)
			)
			(layer "F.SilkS")
		)
		(fp_line
			(start 0.7874 -0.4064)
			(end 0.7874 0.4064)
			(stroke
				(width 0.1524)
				(type default)
			)
			(layer "F.SilkS")
		)
		(fp_line
			(start 0.7874 0.4064)
			(end -0.7874 0.4064)
			(stroke
				(width 0.1524)
				(type default)
			)
			(layer "F.SilkS")
		)
		(fp_line
			(start -0.67945 -0.305054)
			(end -0.12065 -0.305054)
			(stroke
				(width 0.1)
				(type default)
			)
			(layer "F.Fab")
		)
		(fp_line
			(start -0.67945 0.3048)
			(end -0.67945 -0.305054)
			(stroke
				(width 0.1)
				(type default)
			)
			(layer "F.Fab")
		)
		(fp_line
			(start -0.12065 -0.305054)
			(end -0.12065 -0.2794)
			(stroke
				(width 0.1)
				(type default)
			)
			(layer "F.Fab")
		)
		(fp_line
			(start -0.12065 -0.2794)
			(end 0.12065 -0.2794)
			(stroke
				(width 0.1)
				(type default)
			)
			(layer "F.Fab")
		)
		(fp_line
			(start -0.12065 0.2794)
			(end -0.12065 0.3048)
			(stroke
				(width 0.1)
				(type default)
			)
			(layer "F.Fab")
		)
		(fp_line
			(start -0.12065 0.3048)
			(end -0.67945 0.3048)
			(stroke
				(width 0.1)
				(type default)
			)
			(layer "F.Fab")
		)
		(fp_line
			(start 0.120396 0.2794)
			(end -0.12065 0.2794)
			(stroke
				(width 0.1)
				(type default)
			)
			(layer "F.Fab")
		)
		(fp_line
			(start 0.120396 0.3048)
			(end 0.120396 0.2794)
			(stroke
				(width 0.1)
				(type default)
			)
			(layer "F.Fab")
		)
		(fp_line
			(start 0.12065 -0.3048)
			(end 0.67945 -0.3048)
			(stroke
				(width 0.1)
				(type default)
			)
			(layer "F.Fab")
		)
		(fp_line
			(start 0.12065 -0.2794)
			(end 0.12065 -0.3048)
			(stroke
				(width 0.1)
				(type default)
			)
			(layer "F.Fab")
		)
		(fp_line
			(start 0.67945 -0.3048)
			(end 0.67945 0.3048)
			(stroke
				(width 0.1)
				(type default)
			)
			(layer "F.Fab")
		)
		(fp_line
			(start 0.67945 0.3048)
			(end 0.120396 0.3048)
			(stroke
				(width 0.1)
				(type default)
			)
			(layer "F.Fab")
		)
		(pad "1" smd circle
			(at -0.40005 0)
			(size 0 0)
			(layers "F.Cu" "F.Mask" "F.Paste")
			(net "OCP_V3_2_PWRBRK_BUFF_N")
		)
		(pad "2" smd circle
			(at 0.40005 0)
			(size 0 0)
			(layers "F.Cu" "F.Mask" "F.Paste")
			(net "OCP_V3_2_PWRBRK_N")
		)
	)
	(footprint ""
		(layer "F.Cu")
		(at 445.157098 -93.484192 180)
		(property "Reference" "R3627"
			(at 0 0 180)
			(layer "F.SilkS")
			(hide yes)
			(effects
				(font
					(size 1.27 1.27)
				)
			)
		)
		(property "Value" ""
			(at 0 0 180)
			(layer "F.Fab")
			(effects
				(font
					(size 1.27 1.27)
				)
			)
		)
		(duplicate_pad_numbers_are_jumpers no)
		(fp_line
			(start 0.7874 0.4064)
			(end -0.7874 0.4064)
			(stroke
				(width 0.1524)
				(type default)
			)
			(layer "F.SilkS")
		)
		(fp_line
			(start 0.7874 -0.4064)
			(end 0.7874 0.4064)
			(stroke
				(width 0.1524)
				(type default)
			)
			(layer "F.SilkS")
		)
		(fp_line
			(start -0.7874 0.4064)
			(end -0.7874 -0.4064)
			(stroke
				(width 0.1524)
				(type default)
			)
			(layer "F.SilkS")
		)
		(fp_line
			(start -0.7874 -0.4064)
			(end 0.7874 -0.4064)
			(stroke
				(width 0.1524)
				(type default)
			)
			(layer "F.SilkS")
		)
		(fp_line
			(start 0.67945 0.3048)
			(end 0.120396 0.3048)
			(stroke
				(width 0.1)
				(type default)
			)
			(layer "F.Fab")
		)
		(fp_line
			(start 0.67945 -0.3048)
			(end 0.67945 0.3048)
			(stroke
				(width 0.1)
				(type default)
			)
			(layer "F.Fab")
		)
		(fp_line
			(start 0.12065 -0.2794)
			(end 0.12065 -0.3048)
			(stroke
				(width 0.1)
				(type default)
			)
			(layer "F.Fab")
		)
		(fp_line
			(start 0.12065 -0.3048)
			(end 0.67945 -0.3048)
			(stroke
				(width 0.1)
				(type default)
			)
			(layer "F.Fab")
		)
		(fp_line
			(start 0.120396 0.3048)
			(end 0.120396 0.2794)
			(stroke
				(width 0.1)
				(type default)
			)
			(layer "F.Fab")
		)
		(fp_line
			(start 0.120396 0.2794)
			(end -0.12065 0.2794)
			(stroke
				(width 0.1)
				(type default)
			)
			(layer "F.Fab")
		)
		(fp_line
			(start -0.12065 0.3048)
			(end -0.67945 0.3048)
			(stroke
				(width 0.1)
				(type default)
			)
			(layer "F.Fab")
		)
		(fp_line
			(start -0.12065 0.2794)
			(end -0.12065 0.3048)
			(stroke
				(width 0.1)
				(type default)
			)
			(layer "F.Fab")
		)
		(fp_line
			(start -0.12065 -0.2794)
			(end 0.12065 -0.2794)
			(stroke
				(width 0.1)
				(type default)
			)
			(layer "F.Fab")
		)
		(fp_line
			(start -0.12065 -0.305054)
			(end -0.12065 -0.2794)
			(stroke
				(width 0.1)
				(type default)
			)
			(layer "F.Fab")
		)
		(fp_line
			(start -0.67945 0.3048)
			(end -0.67945 -0.305054)
			(stroke
				(width 0.1)
				(type default)
			)
			(layer "F.Fab")
		)
		(fp_line
			(start -0.67945 -0.305054)
			(end -0.12065 -0.305054)
			(stroke
				(width 0.1)
				(type default)
			)
			(layer "F.Fab")
		)
		(pad "1" smd circle
			(at -0.40005 0 180)
			(size 0 0)
			(layers "F.Cu" "F.Mask" "F.Paste")
			(net "P3V3_AUX")
		)
		(pad "2" smd circle
			(at 0.40005 0 180)
			(size 0 0)
			(layers "F.Cu" "F.Mask" "F.Paste")
			(net "INA230_1_A0")
		)
	)
	(footprint ""
		(layer "F.Cu")
		(at 113.494312 -130.424682 180)
		(property "Reference" "R2967"
			(at 0 0 180)
			(layer "F.SilkS")
			(hide yes)
			(effects
				(font
					(size 1.27 1.27)
				)
			)
		)
		(property "Value" ""
			(at 0 0 180)
			(layer "F.Fab")
			(effects
				(font
					(size 1.27 1.27)
				)
			)
		)
		(duplicate_pad_numbers_are_jumpers no)
		(fp_line
			(start 0.7874 0.4064)
			(end -0.7874 0.4064)
			(stroke
				(width 0.1524)
				(type default)
			)
			(layer "F.SilkS")
		)
		(fp_line
			(start 0.7874 -0.4064)
			(end 0.7874 0.4064)
			(stroke
				(width 0.1524)
				(type default)
			)
			(layer "F.SilkS")
		)
		(fp_line
			(start -0.7874 0.4064)
			(end -0.7874 -0.4064)
			(stroke
				(width 0.1524)
				(type default)
			)
			(layer "F.SilkS")
		)
		(fp_line
			(start -0.7874 -0.4064)
			(end 0.7874 -0.4064)
			(stroke
				(width 0.1524)
				(type default)
			)
			(layer "F.SilkS")
		)
		(fp_line
			(start 0.67945 0.3048)
			(end 0.120396 0.3048)
			(stroke
				(width 0.1)
				(type default)
			)
			(layer "F.Fab")
		)
		(fp_line
			(start 0.67945 -0.3048)
			(end 0.67945 0.3048)
			(stroke
				(width 0.1)
				(type default)
			)
			(layer "F.Fab")
		)
		(fp_line
			(start 0.12065 -0.2794)
			(end 0.12065 -0.3048)
			(stroke
				(width 0.1)
				(type default)
			)
			(layer "F.Fab")
		)
		(fp_line
			(start 0.12065 -0.3048)
			(end 0.67945 -0.3048)
			(stroke
				(width 0.1)
				(type default)
			)
			(layer "F.Fab")
		)
		(fp_line
			(start 0.120396 0.3048)
			(end 0.120396 0.2794)
			(stroke
				(width 0.1)
				(type default)
			)
			(layer "F.Fab")
		)
		(fp_line
			(start 0.120396 0.2794)
			(end -0.12065 0.2794)
			(stroke
				(width 0.1)
				(type default)
			)
			(layer "F.Fab")
		)
		(fp_line
			(start -0.12065 0.3048)
			(end -0.67945 0.3048)
			(stroke
				(width 0.1)
				(type default)
			)
			(layer "F.Fab")
		)
		(fp_line
			(start -0.12065 0.2794)
			(end -0.12065 0.3048)
			(stroke
				(width 0.1)
				(type default)
			)
			(layer "F.Fab")
		)
		(fp_line
			(start -0.12065 -0.2794)
			(end 0.12065 -0.2794)
			(stroke
				(width 0.1)
				(type default)
			)
			(layer "F.Fab")
		)
		(fp_line
			(start -0.12065 -0.305054)
			(end -0.12065 -0.2794)
			(stroke
				(width 0.1)
				(type default)
			)
			(layer "F.Fab")
		)
		(fp_line
			(start -0.67945 0.3048)
			(end -0.67945 -0.305054)
			(stroke
				(width 0.1)
				(type default)
			)
			(layer "F.Fab")
		)
		(fp_line
			(start -0.67945 -0.305054)
			(end -0.12065 -0.305054)
			(stroke
				(width 0.1)
				(type default)
			)
			(layer "F.Fab")
		)
		(pad "1" smd circle
			(at -0.40005 0 180)
			(size 0 0)
			(layers "F.Cu" "F.Mask" "F.Paste")
			(net "SMB_PCIE0_3V3AUX_SCL_R3")
		)
		(pad "2" smd circle
			(at 0.40005 0 180)
			(size 0 0)
			(layers "F.Cu" "F.Mask" "F.Paste")
			(net "SMB_SENSOR_M2_P0_3V3AUX_SCL")
		)
	)
	(footprint ""
		(layer "F.Cu")
		(at 26.684478 -16.099536 90)
		(property "Reference" "C815"
			(at 0 0 90)
			(layer "F.SilkS")
			(hide yes)
			(effects
				(font
					(size 1.27 1.27)
				)
			)
		)
		(property "Value" ""
			(at 0 0 90)
			(layer "F.Fab")
			(effects
				(font
					(size 1.27 1.27)
				)
			)
		)
		(duplicate_pad_numbers_are_jumpers no)
		(fp_line
			(start 0.299974 -0.150114)
			(end 0.299974 0.150114)
			(stroke
				(width 0.1)
				(type default)
			)
			(layer "F.Fab")
		)
		(fp_line
			(start -0.299974 -0.150114)
			(end 0.299974 -0.150114)
			(stroke
				(width 0.1)
				(type default)
			)
			(layer "F.Fab")
		)
		(fp_line
			(start 0.299974 0.150114)
			(end -0.299974 0.150114)
			(stroke
				(width 0.1)
				(type default)
			)
			(layer "F.Fab")
		)
		(fp_line
			(start -0.299974 0.150114)
			(end -0.299974 -0.150114)
			(stroke
				(width 0.1)
				(type default)
			)
			(layer "F.Fab")
		)
		(pad "1" smd rect
			(at -0.2667 0 90)
			(size 0.3048 0.381)
			(layers "F.Cu" "F.Mask" "F.Paste")
			(net "P5E_CPU1_PE1_TX_C_DP<11>")
		)
		(pad "2" smd rect
			(at 0.2667 0 90)
			(size 0.3048 0.381)
			(layers "F.Cu" "F.Mask" "F.Paste")
			(net "P5E_CPU1_PE1_TX_DP<11>")
		)
	)
	(footprint ""
		(layer "F.Cu")
		(at 40.627554 -107.031282)
		(property "Reference" "R3681"
			(at 0 0 0)
			(layer "F.SilkS")
			(hide yes)
			(effects
				(font
					(size 1.27 1.27)
				)
			)
		)
		(property "Value" ""
			(at 0 0 0)
			(layer "F.Fab")
			(effects
				(font
					(size 1.27 1.27)
				)
			)
		)
		(duplicate_pad_numbers_are_jumpers no)
		(fp_line
			(start -0.7874 -0.4064)
			(end 0.7874 -0.4064)
			(stroke
				(width 0.1524)
				(type default)
			)
			(layer "F.SilkS")
		)
		(fp_line
			(start -0.7874 0.4064)
			(end -0.7874 -0.4064)
			(stroke
				(width 0.1524)
				(type default)
			)
			(layer "F.SilkS")
		)
		(fp_line
			(start 0.7874 -0.4064)
			(end 0.7874 0.4064)
			(stroke
				(width 0.1524)
				(type default)
			)
			(layer "F.SilkS")
		)
		(fp_line
			(start 0.7874 0.4064)
			(end -0.7874 0.4064)
			(stroke
				(width 0.1524)
				(type default)
			)
			(layer "F.SilkS")
		)
		(fp_line
			(start -0.67945 -0.305054)
			(end -0.12065 -0.305054)
			(stroke
				(width 0.1)
				(type default)
			)
			(layer "F.Fab")
		)
		(fp_line
			(start -0.67945 0.3048)
			(end -0.67945 -0.305054)
			(stroke
				(width 0.1)
				(type default)
			)
			(layer "F.Fab")
		)
		(fp_line
			(start -0.12065 -0.305054)
			(end -0.12065 -0.2794)
			(stroke
				(width 0.1)
				(type default)
			)
			(layer "F.Fab")
		)
		(fp_line
			(start -0.12065 -0.2794)
			(end 0.12065 -0.2794)
			(stroke
				(width 0.1)
				(type default)
			)
			(layer "F.Fab")
		)
		(fp_line
			(start -0.12065 0.2794)
			(end -0.12065 0.3048)
			(stroke
				(width 0.1)
				(type default)
			)
			(layer "F.Fab")
		)
		(fp_line
			(start -0.12065 0.3048)
			(end -0.67945 0.3048)
			(stroke
				(width 0.1)
				(type default)
			)
			(layer "F.Fab")
		)
		(fp_line
			(start 0.120396 0.2794)
			(end -0.12065 0.2794)
			(stroke
				(width 0.1)
				(type default)
			)
			(layer "F.Fab")
		)
		(fp_line
			(start 0.120396 0.3048)
			(end 0.120396 0.2794)
			(stroke
				(width 0.1)
				(type default)
			)
			(layer "F.Fab")
		)
		(fp_line
			(start 0.12065 -0.3048)
			(end 0.67945 -0.3048)
			(stroke
				(width 0.1)
				(type default)
			)
			(layer "F.Fab")
		)
		(fp_line
			(start 0.12065 -0.2794)
			(end 0.12065 -0.3048)
			(stroke
				(width 0.1)
				(type default)
			)
			(layer "F.Fab")
		)
		(fp_line
			(start 0.67945 -0.3048)
			(end 0.67945 0.3048)
			(stroke
				(width 0.1)
				(type default)
			)
			(layer "F.Fab")
		)
		(fp_line
			(start 0.67945 0.3048)
			(end 0.120396 0.3048)
			(stroke
				(width 0.1)
				(type default)
			)
			(layer "F.Fab")
		)
		(pad "1" smd rect
			(at -0.40005 0 180)
			(size 0.4572 0.508)
			(layers "F.Cu" "F.Mask" "F.Paste")
			(net "P3V3_AUX_ADC")
		)
		(pad "2" smd rect
			(at 0.40005 0 180)
			(size 0.4572 0.508)
			(layers "F.Cu" "F.Mask" "F.Paste")
			(net "P3V3_AUX_ADC_MAM")
		)
	)
)
